#ISCELL
  pure_quanta quanta_title_block_c *
  *
#ISCELL
  pure_quanta_power cad_note *
  *
#CELL
  pure_quanta genoa_sp5 *
  page12_i159
#ISCELL
  mstr_standard offpage *
  page12_i160
#ISCELL
  mstr_standard offpage *
  page12_i161
#ISCELL
  mstr_standard tap *
  page12_i162
#ISCELL
  mstr_standard tap *
  page12_i163
#ISCELL
  mstr_standard tap *
  page12_i164
#ISCELL
  mstr_standard tap *
  page12_i165
#ISCELL
  mstr_standard tap *
  page12_i166
#ISCELL
  mstr_standard tap *
  page12_i167
#ISCELL
  mstr_standard tap *
  page12_i168
#ISCELL
  mstr_standard tap *
  page12_i169
#ISCELL
  mstr_standard tap *
  page12_i170
#ISCELL
  mstr_standard tap *
  page12_i171
#ISCELL
  mstr_standard tap *
  page12_i172
#ISCELL
  mstr_standard tap *
  page12_i173
#ISCELL
  mstr_standard tap *
  page12_i174
#ISCELL
  mstr_standard tap *
  page12_i175
#ISCELL
  mstr_standard tap *
  page12_i176
#ISCELL
  mstr_standard tap *
  page12_i177
#ISCELL
  mstr_standard tap *
  page12_i178
#ISCELL
  mstr_standard tap *
  page12_i179
#ISCELL
  mstr_standard tap *
  page12_i180
#ISCELL
  mstr_standard tap *
  page12_i181
#ISCELL
  mstr_standard tap *
  page12_i182
#ISCELL
  mstr_standard tap *
  page12_i183
#ISCELL
  mstr_standard tap *
  page12_i184
#ISCELL
  mstr_standard tap *
  page12_i185
#ISCELL
  mstr_standard tap *
  page12_i186
#ISCELL
  mstr_standard tap *
  page12_i187
#ISCELL
  mstr_standard tap *
  page12_i188
#ISCELL
  mstr_standard tap *
  page12_i189
#ISCELL
  mstr_standard tap *
  page12_i190
#ISCELL
  mstr_standard tap *
  page12_i191
#ISCELL
  mstr_standard tap *
  page12_i192
#ISCELL
  mstr_standard tap *
  page12_i193
#ISCELL
  mstr_standard tap *
  page12_i194
#ISCELL
  mstr_standard tap *
  page12_i195
#ISCELL
  mstr_standard offpage *
  page12_i196
#ISCELL
  mstr_standard tap *
  page12_i197
#ISCELL
  mstr_standard tap *
  page12_i198
#ISCELL
  mstr_standard tap *
  page12_i199
#ISCELL
  mstr_standard tap *
  page12_i200
#ISCELL
  mstr_standard tap *
  page12_i201
#ISCELL
  mstr_standard tap *
  page12_i202
#ISCELL
  mstr_standard tap *
  page12_i203
#ISCELL
  mstr_standard tap *
  page12_i204
#ISCELL
  mstr_standard tap *
  page12_i205
#ISCELL
  mstr_standard tap *
  page12_i206
#ISCELL
  mstr_standard tap *
  page12_i207
#ISCELL
  mstr_standard tap *
  page12_i208
#ISCELL
  mstr_standard tap *
  page12_i209
#ISCELL
  mstr_standard tap *
  page12_i210
#ISCELL
  mstr_standard tap *
  page12_i211
#ISCELL
  mstr_standard tap *
  page12_i212
#ISCELL
  mstr_standard tap *
  page12_i213
#ISCELL
  mstr_standard tap *
  page12_i214
#ISCELL
  mstr_standard tap *
  page12_i215
#ISCELL
  mstr_standard tap *
  page12_i216
#ISCELL
  mstr_standard tap *
  page12_i217
#ISCELL
  mstr_standard tap *
  page12_i218
#ISCELL
  mstr_standard tap *
  page12_i219
#ISCELL
  mstr_standard tap *
  page12_i220
#ISCELL
  mstr_standard tap *
  page12_i221
#ISCELL
  mstr_standard tap *
  page12_i222
#ISCELL
  mstr_standard tap *
  page12_i223
#ISCELL
  mstr_standard tap *
  page12_i224
#ISCELL
  mstr_standard tap *
  page12_i225
#ISCELL
  mstr_standard tap *
  page12_i226
#ISCELL
  mstr_standard tap *
  page12_i227
#ISCELL
  mstr_standard tap *
  page12_i228
#ISCELL
  mstr_standard tap *
  page12_i229
#ISCELL
  mstr_standard tap *
  page12_i230
#ISCELL
  mstr_standard tap *
  page12_i231
#ISCELL
  mstr_standard tap *
  page12_i232
#ISCELL
  mstr_standard tap *
  page12_i233
#ISCELL
  mstr_standard offpage *
  page12_i234
#ISCELL
  mstr_standard tap *
  page12_i235
#ISCELL
  mstr_standard tap *
  page12_i236
#ISCELL
  mstr_standard tap *
  page12_i237
#ISCELL
  mstr_standard tap *
  page12_i238
#ISCELL
  mstr_standard tap *
  page12_i239
#ISCELL
  mstr_standard tap *
  page12_i240
#ISCELL
  mstr_standard tap *
  page12_i241
#ISCELL
  mstr_standard tap *
  page12_i242
#ISCELL
  mstr_standard tap *
  page12_i243
#ISCELL
  mstr_standard tap *
  page12_i244
#ISCELL
  mstr_standard tap *
  page12_i245
#ISCELL
  mstr_standard tap *
  page12_i246
#ISCELL
  mstr_standard tap *
  page12_i247
#ISCELL
  mstr_standard tap *
  page12_i248
#ISCELL
  mstr_standard tap *
  page12_i249
#ISCELL
  mstr_standard tap *
  page12_i250
#ISCELL
  mstr_standard tap *
  page12_i251
#ISCELL
  mstr_standard tap *
  page12_i252
#ISCELL
  mstr_standard tap *
  page12_i253
#ISCELL
  mstr_standard tap *
  page12_i254
#ISCELL
  mstr_standard tap *
  page12_i255
#ISCELL
  mstr_standard tap *
  page12_i256
#ISCELL
  mstr_standard tap *
  page12_i257
#ISCELL
  mstr_standard tap *
  page12_i258
#ISCELL
  mstr_standard tap *
  page12_i259
#ISCELL
  mstr_standard tap *
  page12_i260
#ISCELL
  mstr_standard tap *
  page12_i261
#ISCELL
  mstr_standard tap *
  page12_i262
#ISCELL
  mstr_standard tap *
  page12_i263
#ISCELL
  mstr_standard tap *
  page12_i264
#ISCELL
  mstr_standard tap *
  page12_i265
#ISCELL
  mstr_standard tap *
  page12_i266
#ISCELL
  mstr_standard tap *
  page12_i267
#ISCELL
  mstr_standard tap *
  page12_i268
#ISCELL
  mstr_standard tap *
  page12_i269
#ISCELL
  mstr_standard tap *
  page12_i270
#ISCELL
  mstr_standard tap *
  page12_i271
#ISCELL
  standard offpage *
  page12_i272
#ISCELL
  standard offpage *
  page12_i273
#ISCELL
  mstr_standard tap *
  page12_i274
#ISCELL
  mstr_standard tap *
  page12_i275
#ISCELL
  mstr_standard tap *
  page12_i276
#ISCELL
  mstr_standard tap *
  page12_i277
#ISCELL
  mstr_standard tap *
  page12_i278
#ISCELL
  mstr_standard tap *
  page12_i279
#ISCELL
  mstr_standard tap *
  page12_i280
#ISCELL
  mstr_standard tap *
  page12_i281
#ISCELL
  mstr_standard tap *
  page12_i282
#ISCELL
  standard offpage *
  page12_i283
#ISCELL
  standard offpage *
  page12_i284
#ISCELL
  mstr_standard tap *
  page12_i285
#ISCELL
  mstr_standard tap *
  page12_i286
#ISCELL
  mstr_standard tap *
  page12_i287
#ISCELL
  mstr_standard tap *
  page12_i288
#ISCELL
  mstr_standard tap *
  page12_i289
#ISCELL
  mstr_standard tap *
  page12_i290
#ISCELL
  mstr_standard tap *
  page12_i291
#ISCELL
  mstr_standard tap *
  page12_i292
#ISCELL
  mstr_standard tap *
  page12_i293
#ISCELL
  mstr_standard tap *
  page12_i294
#ISCELL
  mstr_standard tap *
  page12_i295
#ISCELL
  mstr_standard tap *
  page12_i296
#ISCELL
  mstr_standard tap *
  page12_i297
#ISCELL
  mstr_standard tap *
  page12_i298
#ISCELL
  mstr_standard tap *
  page12_i299
#ISCELL
  mstr_standard tap *
  page12_i300
#ISCELL
  mstr_standard tap *
  page12_i301
#ISCELL
  standard offpage *
  page12_i302
#ISCELL
  standard offpage *
  page12_i303
#ISCELL
  standard offpage *
  page12_i304
#ISCELL
  standard offpage *
  page12_i305
#ISCELL
  standard offpage *
  page12_i306
#ISCELL
  standard offpage *
  page12_i307
#ISCELL
  standard offpage *
  page12_i308
#ISCELL
  mstr_standard offpage *
  page12_i309
#ISCELL
  standard offpage *
  page12_i310
#ISCELL
  standard offpage *
  page12_i311
#ISCELL
  standard offpage *
  page12_i312
#ISCELL
  standard offpage *
  page12_i313
#CELL
  pure_quanta q_res *
  page12_i314
#ISCELL
  mstr_standard offpage *
  page12_i315
#ISCELL
  standard offpage *
  page12_i316
